(kicad_pcb
	(version 20260206)
	(generator "pcbnew")
	(generator_version "10.0")
	(general
		(thickness 1.6)
		(legacy_teardrops no)
	)
	(paper "A4")
	(title_block
		(title "peb — Lightning_PEB_BRD.brd")
		(comment 1 "Lightning (Wiwynn / Facebook NVMe JBOF) / footprints 240-246 of 2563")
	)
	(layers
		(0 "F.Cu" signal "TOP")
		(4 "In1.Cu" signal "L2GND")
		(6 "In2.Cu" signal "L3")
		(8 "In3.Cu" signal "L4VCC")
		(10 "In4.Cu" signal "L5VCC")
		(12 "In5.Cu" signal "L6")
		(14 "In6.Cu" signal "L7GND")
		(2 "B.Cu" signal "BOTTOM")
		(9 "F.Adhes" user "F.Adhesive")
		(11 "B.Adhes" user "B.Adhesive")
		(13 "F.Paste" user "Package Geometry/Pastemask Top")
		(15 "B.Paste" user "Package Geometry/Pastemask Bottom")
		(5 "F.SilkS" user "Ref Des/Silkscreen Top")
		(7 "B.SilkS" user "Ref Des/Silkscreen Bottom")
		(1 "F.Mask" user "Board Geometry/Soldermask Top")
		(3 "B.Mask" user "Board Geometry/Soldermask Bottom")
		(17 "Dwgs.User" user "User.Drawings")
		(19 "Cmts.User" user "User.Comments")
		(21 "Eco1.User" user "User.Eco1")
		(23 "Eco2.User" user "User.Eco2")
		(25 "Edge.Cuts" user "Board Geometry/Outline")
		(27 "Margin" user)
		(31 "F.CrtYd" user "Package Geometry/Place Bound Top")
		(29 "B.CrtYd" user "Package Geometry/Place Bound Bottom")
		(35 "F.Fab" user "Ref Des/Assembly Top")
		(33 "B.Fab" user "Ref Des/Assembly Bottom")
	)
	(footprint ""
		(layer "F.Cu")
		(at 297.044618 -33.496504 180)
		(property "Reference" "R727"
			(at 0 0 180)
			(layer "F.SilkS")
			(hide yes)
			(effects
				(font
					(size 1.27 1.27)
				)
			)
		)
		(property "Value" "0R2J-2-GP"
			(at 0.064008 -3.993896 180)
			(unlocked yes)
			(layer "F.Fab")
			(hide yes)
			(effects
				(font
					(size 1.016 1.016)
					(thickness 0.1524)
				)
			)
		)
		(property "Device Type" "R402H16"
			(at 0.064008 -5.517896 180)
			(unlocked yes)
			(layer "F.Fab")
			(hide yes)
			(effects
				(font
					(size 1.016 1.016)
					(thickness 0.1524)
				)
			)
		)
		(duplicate_pad_numbers_are_jumpers no)
		(fp_line
			(start 0.508 -0.9398)
			(end -0.508 -0.9398)
			(stroke
				(width 0.1524)
				(type default)
			)
			(layer "F.SilkS")
		)
		(fp_line
			(start -0.508 -0.9398)
			(end -0.508 0.9398)
			(stroke
				(width 0.1524)
				(type default)
			)
			(layer "F.SilkS")
		)
		(fp_rect
			(start -0.508 0.9398)
			(end 0.508 -0.9398)
			(stroke
				(width 0)
				(type default)
			)
			(fill no)
			(layer "F.CrtYd")
		)
		(fp_rect
			(start -0.508 0.9398)
			(end 0.508 -0.9398)
			(stroke
				(width 0)
				(type default)
			)
			(fill no)
			(layer "F.Fab")
		)
		(pad "1" smd custom
			(at 0 -0.4445 180)
			(size 0.1397 0.1397)
			(layers "F.Cu" "F.Mask" "F.Paste")
			(net "8644_USB_DN6")
			(options
				(clearance outline)
				(anchor circle)
			)
			(primitives
				(gr_poly
					(pts
						(arc
							(start -0.1778 -0.2794)
							(mid -0.249642 -0.249642)
							(end -0.2794 -0.1778)
						)
						(arc
							(start -0.2794 0.1778)
							(mid -0.249642 0.249642)
							(end -0.1778 0.2794)
						)
						(arc
							(start 0.1778 0.2794)
							(mid 0.249642 0.249642)
							(end 0.2794 0.1778)
						)
						(arc
							(start 0.2794 -0.1778)
							(mid 0.249642 -0.249642)
							(end 0.1778 -0.2794)
						)
					)
					(width 0)
					(fill yes)
				)
			)
		)
		(pad "2" smd custom
			(at 0 0.4445 180)
			(size 0.1397 0.1397)
			(layers "F.Cu" "F.Mask" "F.Paste")
			(net "P3V3_STBY")
			(options
				(clearance outline)
				(anchor circle)
			)
			(primitives
				(gr_poly
					(pts
						(arc
							(start -0.1778 -0.2794)
							(mid -0.249642 -0.249642)
							(end -0.2794 -0.1778)
						)
						(arc
							(start -0.2794 0.1778)
							(mid -0.249642 0.249642)
							(end -0.1778 0.2794)
						)
						(arc
							(start 0.1778 0.2794)
							(mid 0.249642 0.249642)
							(end 0.2794 0.1778)
						)
						(arc
							(start 0.2794 -0.1778)
							(mid 0.249642 -0.249642)
							(end 0.1778 -0.2794)
						)
					)
					(width 0)
					(fill yes)
				)
			)
		)
	)
	(footprint ""
		(layer "F.Cu")
		(at 15.3035 -50.8254 90)
		(property "Reference" "D15"
			(at 0 0 90)
			(layer "F.SilkS")
			(hide yes)
			(effects
				(font
					(size 1.27 1.27)
				)
			)
		)
		(property "Value" "PGB1010603MR-GP"
			(at -0.0254 -2.8956 90)
			(unlocked yes)
			(layer "F.Fab")
			(hide yes)
			(effects
				(font
					(size 1.016 1.016)
					(thickness 0.1524)
				)
			)
		)
		(property "Device Type" "L1608-UH15"
			(at -0.0254 -4.4196 90)
			(unlocked yes)
			(layer "F.Fab")
			(hide yes)
			(effects
				(font
					(size 1.016 1.016)
					(thickness 0.1524)
				)
			)
		)
		(duplicate_pad_numbers_are_jumpers no)
		(fp_line
			(start 0.254 0)
			(end -0.254 0)
			(stroke
				(width 0.2032)
				(type default)
			)
			(layer "F.SilkS")
		)
		(fp_rect
			(start -0.5842 1.3335)
			(end 0.5842 -1.3335)
			(stroke
				(width 0)
				(type default)
			)
			(fill no)
			(layer "F.CrtYd")
		)
		(fp_rect
			(start -0.5842 1.3335)
			(end 0.5842 -1.3335)
			(stroke
				(width 0)
				(type default)
			)
			(fill no)
			(layer "F.Fab")
		)
		(pad "1" smd custom
			(at 0 -0.762 90)
			(size 0.2159 0.2159)
			(layers "F.Cu" "F.Mask" "F.Paste")
			(net "NIC0_MDI0_P1_R")
			(options
				(clearance outline)
				(anchor circle)
			)
			(primitives
				(gr_poly
					(pts
						(arc
							(start -0.3302 -0.4318)
							(mid -0.402042 -0.402042)
							(end -0.4318 -0.3302)
						)
						(arc
							(start -0.4318 0.3302)
							(mid -0.402042 0.402042)
							(end -0.3302 0.4318)
						)
						(arc
							(start 0.3302 0.4318)
							(mid 0.402042 0.402042)
							(end 0.4318 0.3302)
						)
						(arc
							(start 0.4318 -0.3302)
							(mid 0.402042 -0.402042)
							(end 0.3302 -0.4318)
						)
					)
					(width 0)
					(fill yes)
				)
			)
		)
		(pad "2" smd custom
			(at 0 0.762 90)
			(size 0.2159 0.2159)
			(layers "F.Cu" "F.Mask" "F.Paste")
			(net "GND")
			(options
				(clearance outline)
				(anchor circle)
			)
			(primitives
				(gr_poly
					(pts
						(arc
							(start -0.3302 -0.4318)
							(mid -0.402042 -0.402042)
							(end -0.4318 -0.3302)
						)
						(arc
							(start -0.4318 0.3302)
							(mid -0.402042 0.402042)
							(end -0.3302 0.4318)
						)
						(arc
							(start 0.3302 0.4318)
							(mid 0.402042 0.402042)
							(end 0.4318 0.3302)
						)
						(arc
							(start 0.4318 -0.3302)
							(mid 0.402042 -0.402042)
							(end 0.3302 -0.4318)
						)
					)
					(width 0)
					(fill yes)
				)
			)
		)
	)
	(footprint ""
		(layer "F.Cu")
		(at 137.79246 -41.173654 180)
		(property "Reference" "R754"
			(at 0 0 180)
			(layer "F.SilkS")
			(hide yes)
			(effects
				(font
					(size 1.27 1.27)
				)
			)
		)
		(property "Value" "33D2R2F-GP"
			(at 0.064008 -3.993896 180)
			(unlocked yes)
			(layer "F.Fab")
			(hide yes)
			(effects
				(font
					(size 1.016 1.016)
					(thickness 0.1524)
				)
			)
		)
		(property "Device Type" "R402H16"
			(at 0.064008 -5.517896 180)
			(unlocked yes)
			(layer "F.Fab")
			(hide yes)
			(effects
				(font
					(size 1.016 1.016)
					(thickness 0.1524)
				)
			)
		)
		(duplicate_pad_numbers_are_jumpers no)
		(fp_line
			(start 0.508 -0.9398)
			(end -0.508 -0.9398)
			(stroke
				(width 0.1524)
				(type default)
			)
			(layer "F.SilkS")
		)
		(fp_line
			(start -0.508 -0.9398)
			(end -0.508 0.9398)
			(stroke
				(width 0.1524)
				(type default)
			)
			(layer "F.SilkS")
		)
		(fp_rect
			(start -0.508 0.9398)
			(end 0.508 -0.9398)
			(stroke
				(width 0)
				(type default)
			)
			(fill no)
			(layer "F.CrtYd")
		)
		(fp_rect
			(start -0.508 0.9398)
			(end 0.508 -0.9398)
			(stroke
				(width 0)
				(type default)
			)
			(fill no)
			(layer "F.Fab")
		)
		(pad "1" smd custom
			(at 0 -0.4445 180)
			(size 0.1397 0.1397)
			(layers "F.Cu" "F.Mask" "F.Paste")
			(net "DUT_TDO")
			(options
				(clearance outline)
				(anchor circle)
			)
			(primitives
				(gr_poly
					(pts
						(arc
							(start -0.1778 -0.2794)
							(mid -0.249642 -0.249642)
							(end -0.2794 -0.1778)
						)
						(arc
							(start -0.2794 0.1778)
							(mid -0.249642 0.249642)
							(end -0.1778 0.2794)
						)
						(arc
							(start 0.1778 0.2794)
							(mid 0.249642 0.249642)
							(end 0.2794 0.1778)
						)
						(arc
							(start 0.2794 -0.1778)
							(mid 0.249642 -0.249642)
							(end 0.1778 -0.2794)
						)
					)
					(width 0)
					(fill yes)
				)
			)
		)
		(pad "2" smd custom
			(at 0 0.4445 180)
			(size 0.1397 0.1397)
			(layers "F.Cu" "F.Mask" "F.Paste")
			(net "EJTAG_TDO")
			(options
				(clearance outline)
				(anchor circle)
			)
			(primitives
				(gr_poly
					(pts
						(arc
							(start -0.1778 -0.2794)
							(mid -0.249642 -0.249642)
							(end -0.2794 -0.1778)
						)
						(arc
							(start -0.2794 0.1778)
							(mid -0.249642 0.249642)
							(end -0.1778 0.2794)
						)
						(arc
							(start 0.1778 0.2794)
							(mid 0.249642 0.249642)
							(end 0.2794 0.1778)
						)
						(arc
							(start 0.2794 -0.1778)
							(mid 0.249642 -0.249642)
							(end 0.1778 -0.2794)
						)
					)
					(width 0)
					(fill yes)
				)
			)
		)
	)
	(footprint ""
		(layer "F.Cu")
		(at 307.975 -68.834 180)
		(property "Reference" "C630"
			(at 0 0 180)
			(layer "F.SilkS")
			(hide yes)
			(effects
				(font
					(size 1.27 1.27)
				)
			)
		)
		(property "Value" "SC10U16V5KX-1-GP"
			(at -0.0762 -6.1214 180)
			(unlocked yes)
			(layer "F.Fab")
			(hide yes)
			(effects
				(font
					(size 1.016 1.016)
					(thickness 0.1524)
				)
			)
		)
		(property "Device Type" "C805H54"
			(at -0.0762 -8.1534 180)
			(unlocked yes)
			(layer "F.Fab")
			(hide yes)
			(effects
				(font
					(size 1.016 1.016)
					(thickness 0.1524)
				)
			)
		)
		(duplicate_pad_numbers_are_jumpers no)
		(fp_line
			(start 0.635 0)
			(end -0.635 0)
			(stroke
				(width 0.508)
				(type default)
			)
			(layer "F.SilkS")
		)
		(fp_rect
			(start -0.9652 1.778)
			(end 0.9652 -1.778)
			(stroke
				(width 0)
				(type default)
			)
			(fill no)
			(layer "F.CrtYd")
		)
		(fp_poly
			(pts
				(xy -0.9652 -1.778) (xy 0.9652 -1.778) (xy 0.9652 1.778) (xy -0.9652 1.778)
			)
			(stroke
				(width 0)
				(type default)
			)
			(fill no)
			(layer "F.Fab")
		)
		(pad "1" smd rect
			(at 0 -0.9652 180)
			(size 1.397 1.143)
			(layers "F.Cu" "F.Mask" "F.Paste")
			(net "DUT_VDD")
		)
		(pad "2" smd rect
			(at 0 0.9652 180)
			(size 1.397 1.143)
			(layers "F.Cu" "F.Mask" "F.Paste")
			(net "GND")
		)
	)
	(footprint ""
		(layer "F.Cu")
		(at 31.41472 -79.429356)
		(property "Reference" "PC73"
			(at 0 0 0)
			(layer "F.SilkS")
			(hide yes)
			(effects
				(font
					(size 1.27 1.27)
				)
			)
		)
		(property "Value" "SC22P50V3JN-GP"
			(at 0 -2.8194 0)
			(unlocked yes)
			(layer "F.Fab")
			(hide yes)
			(effects
				(font
					(size 1.016 1.016)
					(thickness 0.1524)
				)
			)
		)
		(property "Device Type" "C603H36"
			(at 0 -4.3434 0)
			(unlocked yes)
			(layer "F.Fab")
			(hide yes)
			(effects
				(font
					(size 1.016 1.016)
					(thickness 0.1524)
				)
			)
		)
		(duplicate_pad_numbers_are_jumpers no)
		(fp_line
			(start 0.508 0)
			(end -0.508 0)
			(stroke
				(width 0.2032)
				(type default)
			)
			(layer "F.SilkS")
		)
		(fp_rect
			(start -0.5842 1.3335)
			(end 0.5842 -1.3335)
			(stroke
				(width 0)
				(type default)
			)
			(fill no)
			(layer "F.CrtYd")
		)
		(fp_rect
			(start -0.5842 1.3335)
			(end 0.5842 -1.3335)
			(stroke
				(width 0)
				(type default)
			)
			(fill no)
			(layer "F.Fab")
		)
		(pad "1" smd custom
			(at 0 -0.762)
			(size 0.2159 0.2159)
			(layers "F.Cu" "F.Mask" "F.Paste")
			(net "P5V_STBY_LR")
			(options
				(clearance outline)
				(anchor circle)
			)
			(primitives
				(gr_poly
					(pts
						(arc
							(start -0.3302 -0.4318)
							(mid -0.402042 -0.402042)
							(end -0.4318 -0.3302)
						)
						(arc
							(start -0.4318 0.3302)
							(mid -0.402042 0.402042)
							(end -0.3302 0.4318)
						)
						(arc
							(start 0.3302 0.4318)
							(mid 0.402042 0.402042)
							(end 0.4318 0.3302)
						)
						(arc
							(start 0.4318 -0.3302)
							(mid 0.402042 -0.402042)
							(end 0.3302 -0.4318)
						)
					)
					(width 0)
					(fill yes)
				)
			)
		)
		(pad "2" smd custom
			(at 0 0.762)
			(size 0.2159 0.2159)
			(layers "F.Cu" "F.Mask" "F.Paste")
			(net "P5V_STBY_FB")
			(options
				(clearance outline)
				(anchor circle)
			)
			(primitives
				(gr_poly
					(pts
						(arc
							(start -0.3302 -0.4318)
							(mid -0.402042 -0.402042)
							(end -0.4318 -0.3302)
						)
						(arc
							(start -0.4318 0.3302)
							(mid -0.402042 0.402042)
							(end -0.3302 0.4318)
						)
						(arc
							(start 0.3302 0.4318)
							(mid 0.402042 0.402042)
							(end 0.4318 0.3302)
						)
						(arc
							(start 0.4318 -0.3302)
							(mid 0.402042 -0.402042)
							(end 0.3302 -0.4318)
						)
					)
					(width 0)
					(fill yes)
				)
			)
		)
	)
	(footprint ""
		(layer "F.Cu")
		(at 23.4696 -55.118 180)
		(property "Reference" "R603"
			(at 0 0 180)
			(layer "F.SilkS")
			(hide yes)
			(effects
				(font
					(size 1.27 1.27)
				)
			)
		)
		(property "Value" "0R2J-2-GP"
			(at 0.064008 -3.993896 180)
			(unlocked yes)
			(layer "F.Fab")
			(hide yes)
			(effects
				(font
					(size 1.016 1.016)
					(thickness 0.1524)
				)
			)
		)
		(property "Device Type" "R402H16"
			(at 0.064008 -5.517896 180)
			(unlocked yes)
			(layer "F.Fab")
			(hide yes)
			(effects
				(font
					(size 1.016 1.016)
					(thickness 0.1524)
				)
			)
		)
		(duplicate_pad_numbers_are_jumpers no)
		(fp_line
			(start 0.508 -0.9398)
			(end -0.508 -0.9398)
			(stroke
				(width 0.1524)
				(type default)
			)
			(layer "F.SilkS")
		)
		(fp_line
			(start -0.508 -0.9398)
			(end -0.508 0.9398)
			(stroke
				(width 0.1524)
				(type default)
			)
			(layer "F.SilkS")
		)
		(fp_rect
			(start -0.508 0.9398)
			(end 0.508 -0.9398)
			(stroke
				(width 0)
				(type default)
			)
			(fill no)
			(layer "F.CrtYd")
		)
		(fp_rect
			(start -0.508 0.9398)
			(end 0.508 -0.9398)
			(stroke
				(width 0)
				(type default)
			)
			(fill no)
			(layer "F.Fab")
		)
		(pad "1" smd custom
			(at 0 -0.4445 180)
			(size 0.1397 0.1397)
			(layers "F.Cu" "F.Mask" "F.Paste")
			(net "NIC0_MDI0_P3")
			(options
				(clearance outline)
				(anchor circle)
			)
			(primitives
				(gr_poly
					(pts
						(arc
							(start -0.1778 -0.2794)
							(mid -0.249642 -0.249642)
							(end -0.2794 -0.1778)
						)
						(arc
							(start -0.2794 0.1778)
							(mid -0.249642 0.249642)
							(end -0.1778 0.2794)
						)
						(arc
							(start 0.1778 0.2794)
							(mid 0.249642 0.249642)
							(end 0.2794 0.1778)
						)
						(arc
							(start 0.2794 -0.1778)
							(mid 0.249642 -0.249642)
							(end 0.1778 -0.2794)
						)
					)
					(width 0)
					(fill yes)
				)
			)
		)
		(pad "2" smd custom
			(at 0 0.4445 180)
			(size 0.1397 0.1397)
			(layers "F.Cu" "F.Mask" "F.Paste")
			(net "MNG_RX_DP")
			(options
				(clearance outline)
				(anchor circle)
			)
			(primitives
				(gr_poly
					(pts
						(arc
							(start -0.1778 -0.2794)
							(mid -0.249642 -0.249642)
							(end -0.2794 -0.1778)
						)
						(arc
							(start -0.2794 0.1778)
							(mid -0.249642 0.249642)
							(end -0.1778 0.2794)
						)
						(arc
							(start 0.1778 0.2794)
							(mid 0.249642 0.249642)
							(end 0.2794 0.1778)
						)
						(arc
							(start 0.2794 -0.1778)
							(mid 0.249642 -0.249642)
							(end 0.1778 -0.2794)
						)
					)
					(width 0)
					(fill yes)
				)
			)
		)
	)
	(footprint ""
		(layer "F.Cu")
		(at 80.607916 -212.420454 180)
		(property "Reference" "C351"
			(at 0 0 180)
			(layer "F.SilkS")
			(hide yes)
			(effects
				(font
					(size 1.27 1.27)
				)
			)
		)
		(property "Value" "SCD22U10V2KX-1GP"
			(at 1.1811 -2.7051 180)
			(unlocked yes)
			(layer "F.Fab")
			(hide yes)
			(effects
				(font
					(size 1.016 1.016)
					(thickness 0.1524)
				)
			)
		)
		(property "Device Type" "C402H22"
			(at 1.1811 -4.2291 180)
			(unlocked yes)
			(layer "F.Fab")
			(hide yes)
			(effects
				(font
					(size 1.016 1.016)
					(thickness 0.1524)
				)
			)
		)
		(duplicate_pad_numbers_are_jumpers no)
		(fp_rect
			(start -0.4318 0.9525)
			(end 0.4318 -0.9525)
			(stroke
				(width 0)
				(type default)
			)
			(fill no)
			(layer "F.CrtYd")
		)
		(fp_rect
			(start -0.4318 0.9525)
			(end 0.4318 -0.9525)
			(stroke
				(width 0)
				(type default)
			)
			(fill no)
			(layer "F.Fab")
		)
		(pad "1" smd custom
			(at 0 -0.4445 180)
			(size 0.1524 0.1524)
			(layers "F.Cu" "F.Mask" "F.Paste")
			(net "PCIE_TX_CAP_N68")
			(options
				(clearance outline)
				(anchor circle)
			)
			(primitives
				(gr_poly
					(pts
						(arc
							(start 0.3048 -0.2032)
							(mid 0.275042 -0.275042)
							(end 0.2032 -0.3048)
						)
						(arc
							(start -0.2032 -0.3048)
							(mid -0.275042 -0.275042)
							(end -0.3048 -0.2032)
						)
						(arc
							(start -0.3048 0.2032)
							(mid -0.275042 0.275042)
							(end -0.2032 0.3048)
						)
						(arc
							(start 0.2032 0.3048)
							(mid 0.275042 0.275042)
							(end 0.3048 0.2032)
						)
					)
					(width 0)
					(fill yes)
				)
			)
		)
		(pad "2" smd custom
			(at 0 0.4445 180)
			(size 0.1524 0.1524)
			(layers "F.Cu" "F.Mask" "F.Paste")
			(net "PCIE_TX_N68")
			(options
				(clearance outline)
				(anchor circle)
			)
			(primitives
				(gr_poly
					(pts
						(arc
							(start 0.3048 -0.2032)
							(mid 0.275042 -0.275042)
							(end 0.2032 -0.3048)
						)
						(arc
							(start -0.2032 -0.3048)
							(mid -0.275042 -0.275042)
							(end -0.3048 -0.2032)
						)
						(arc
							(start -0.3048 0.2032)
							(mid -0.275042 0.275042)
							(end -0.2032 0.3048)
						)
						(arc
							(start 0.2032 0.3048)
							(mid 0.275042 0.275042)
							(end 0.3048 0.2032)
						)
					)
					(width 0)
					(fill yes)
				)
			)
		)
	)
)
